# T6G (Grand Teton) — schematic netlist excerpt (pin names and nets, part order shuffled) for the footprints in the layout excerpt that follows; sources: Cadence DE-HDL packaged netlist, KiCad conversion of 04192023_DAF0TMB3IC0_F0TG_MB_C_brd_V02_OCP.brd

J41  SCONN168_ME1016810202011  IO  pkg CON_F168S2H7D_P0-6W2-95_LUH  page 150
  GND_A1  = SMB_OCP_SFF_3V3AUX_SCL_R0
  GND_A2  = SMB_OCP_SFF_3V3AUX_SDA_R0
  GND_A3  = SMB_CPU0_CPU1_APML_SCL_R
  GND_A4  = SMB_CPU0_CPU1_APML_SDA_R
  GND_A5  = SMB_VR_3V3AUX_SCL_R0
  GND_A6  = SMB_VR_3V3AUX_SDA_R0
  SMCLK  = SMB_CPU0_CPU1_SEC_SCL_R
  SMDAT  = SMB_CPU0_CPU1_SEC_SDA_R
  \smrst#\  = I3C_BMC_SWB_SCL
  \prsnta#\  = I3C_BMC_SWB_SDA
  \perst1#\  = SMB_OCP_V3_2_3V3AUX_SCL_R0
  \prsntb2#\  = SMB_OCP_V3_2_3V3AUX_SDA_R0
  GND_A13  = GND
  REFCLKN1  = CLK_100M_CPU0_CLK01_DP
  REFCLKP1  = CLK_100M_CPU0_CLK01_DN
  GND_A16  = GND
  PERN0  = P2E_CPU0_P5_TX_C_DP
  PERP0  = P2E_CPU0_P5_TX_C_DN
  GND_A19  = GND
  PERN1  = P2E_CPU0_P5_RX_DP
  PERP1  = P2E_CPU0_P5_RX_DN
  GND_A22  = GND
  PERN2  = SMB_PCIE0_3V3AUX_SCL
  PERP2  = SMB_PCIE0_3V3AUX_SDA
  GND_A25  = SMB_PMBUS_3V3AUX_SCL_R0
  PERN3  = SMB_PMBUS_3V3AUX_SDA_R0
  PERP3  = SMB_1_PLD_3V3AUX_SCL_R3
  GND_A28  = SMB_1_PLD_3V3AUX_SDA_R3
  GND_A29  = SMB_FAN_3V3AUX_SCL
  PERN4  = SMB_FAN_3V3AUX_SDA
  PERP4  = SMB_PCIE2_3V3AUX_SCL_R0
  GND_A32  = SMB_PCIE2_3V3AUX_SDA_R0
  PERN5  = GND
  PERP5  = JTAG_SCM_TCK
  GND_A35  = JTAG_SCM_TMS
  PERN6  = JTAG_SCM_TDI_R
  PERP6  = JTAG_SCM_TDO_R
  GND_A38  = SMB_PCIE3_3V3AUX_SCL_R
  PERN7  = SMB_PCIE3_3V3AUX_SDA_R
  PERP7  = SMB_HOST_CLK_3V3AUX_SCL_R0
  GND_A41  = SMB_HOST_CLK_3V3AUX_SDA_R0
  \prsntb1#\  = GND
  GND_A43  = FW_RECOVERY
  PERN8  = PWRGD_PS_PWROK_R
  PERP8  = TP_STBY_EN
  GND_A46  = RST_MB_STBY_R_N
  PERN9  = SCM_SYS_PWRBTN_R_N
  PERP9  = SCM_SYS_PWROK_R1
  GND_A49  = SCM_HDT_DBREQ_N
  PERN10  = PU_JTAG_DBP_BMC_PRDY_N
  PERP10  = FM_RST_PERST_SCM_N
  GND_A52  = FM_UARTSW_MSB_R
  PERN11  = SCM_ROT_CPU_RST_N
  PERP11  = TP_CHASI
  GND_A55  = FM_UARTSW_LSB_R
  PERN12  = IRQ0_A56
  PERP12  = FM_SCM_PRSNT1_N
  GND_A58  = GND
  PERN13  = USB3_CPU0_BMC_RX_DP
  PERP13  = USB3_CPU0_BMC_RX_DN
  GND_A61  = GND
  PERN14  = TP_PCIE_RXP<1>
  PERP14  = TP_PCIE_RXN<1>
  GND_A64  = GND
  PERN15  = P2E_MB_BMC_RX_BUF_DP<0>
  PERP15  = P2E_MB_BMC_RX_BUF_DN<0>
  GND_A67  = GND
  USB_DATN  = CLK_100M_BMC_RC_DP
  USB_DATP  = CLK_100M_BMC_RC_DN
  \pwrbrk0#\  = GND
  \+12v_edge_b1\  = CLK_ESPI_CPU0_CLK1
  \+12v_edge_b2\  = ESPI_CPU0_CS1_N
  \+12v_edge_b3\  = ESPI_CPU0_ALERT_N
  \+12v_edge_b4\  = RST_ESPI_CPU0_RSTOUT_N
  \+12v_edge_b5\  = ESPI_CPU0_D0
  \+12v_edge_b6\  = ESPI_CPU0_D1
  \bif0#\  = ESPI_CPU0_D2
  \bif1#\  = ESPI_CPU0_D3
  \bif2#\  = FM_LPC_ESPI_SEL
  \perst0#\  = GND
  \+3.3v_edge\  = SPI_CPU0_LVC3_SCM_CLK
  AUX_PWR_EN  = SPI_CPU0_LVC3_SCM_CS0_N
  GND_B13  = SPI_CPU0_LVC3_SCM_D0
  REFCLKN0  = SPI_CPU0_LVC3_SCM_D1
  REFCLKP0  = SPI_CPU0_LVC3_SCM_D2
  GND_B16  = SPI_CPU0_LVC3_SCM_D3
  PETN0  = GND
  PETP0  = CLK_50M_RMII_BMC_OCP
  GND_B19  = RMII_OCP_BMC_CRSDV
  PETN1  = RMII_BMC_OCP_TX_EN
  PETP1  = RMII_BMC_OCP_TXD_0
  GND_B22  = RMII_BMC_OCP_TXD_1
  PETN2  = RMII_BMC_OCP_RX_ER
  PETP2  = RMII_OCP_BMC_RXD_0
  GND_B25  = RMII_OCP_BMC_RXD_1
  PETN3  = GND
  PETP3  = TP_PECI_BMC
  GND_B28  = TP_PVCCIO_PECI_BMC
  GND_B29  = SGPIO_SCM_DO_R_<0>
  PETN4  = SGPIO_SCM_CLK_R_<0>
  PETP4  = SGPIO_SCM_DI_R_<0>
  GND_B32  = SGPIO_SCM_LD_R_<0>
  PETN5  = GND
  PETP5  = SGPIO_SCM_DO_R_<1>
  GND_B35  = SGPIO_SCM_CLK_R_<1>
  PETN6  = SGPIO_SCM_DI_R_<1>
  PETP6  = SGPIO_SCM_LD_R_<1>
  GND_B38  = GND
  PETN7  = SGPIO_SCM_RESET_R_N
  PETP7  = SGPIO_SCM_INTR_R1_N
  GND_B41  = SCM_VDD_RTC
  \prsntb0#\  = FM_AC_PWR_BTN_N
  GND_B43  = TP_SPI_2_PLD_CLK
  PETN8  = TP_SPI_2_PLD_CS_N
  PETP8  = TP_SPI_2_PLD_IO0
  GND_B46  = TP_SPI_2_PLD_IO1
  PETN9  = TP_SPI_2_PLD_IO2
  PETP9  = TP_SPI_2_PLD_IO3
  GND_B49  = GND
  PETN10  = USB2_HOST_BMC_B_DP
  PETP10  = USB2_HOST_BMC_B_DN
  GND_B52  = GND
  PETN11  = USB2_CPU0_P1_DP
  PETP11  = USB2_CPU0_P1_DN
  GND_B55  = GND
  PETN12  = USB2_HUB_EXT_DP
  PETP12  = USB2_HUB_EXT_DN
  GND_B58  = GND
  PETN13  = USB3_CPU0_BMC_TX_BUF_C_DP
  PETP13  = USB3_CPU0_BMC_TX_BUF_C_DN
  GND_B61  = GND
  PETN14  = TP_PCIE_TXP<1>
  PETP14  = TP_PCIE_TXN<1>
  GND_B64  = GND
  PETN15  = P2E_MB_BMC_TX_C_DP<0>
  PETP15  = P2E_MB_BMC_TX_C_DN<0>
  GND_B67  = GND
  RFU1_NC_B68  = TP_PCIE_TXP<3>
  RFU1_NC_B69  = TP_BEEP_LED
  \prsntb3#\  = GND
  G1  = GND
  G2  = GND
  G3  = GND
  G4  = GND
  G5  = GND
  \perst2#\  = P12V_SCM
  \perst3#\  = P12V_SCM
  \wake#\  = GND
  RBT_ARB_IN  = GND
  RBT_ARB_OUT  = I3C_SCM_0_SCL
  SLOT_ID1  = I3C_SCM_0_SDA
  RBT_TX_EN  = I3C_SCM_1_SCL
  RBT_TXD1  = I3C_SCM_1_SDA
  RBT_TXD0  = I3C_SCM_2_SCL
  GND_OA10  = I3C_SCM_2_SDA
  REFCLKN3  = I3C_SCM_3_SCL
  REFCLKP3  = I3C_SCM_3_SDA
  GND_OA13  = GND
  RBT_CLK_IN  = VIRTUAL_RESEAT
  NIC_PWR_GOOD  = P12V_SCM
  MAIN_PWR_EN  = P12V_SCM
  \ld#\  = PRSNT0_N
  DATA_IN  = GND
  DATA_OUT  = UART_BMC_BIC_TX
  CLK  = UART_BMC_BIC_BUF_RX
  SLOT_ID0  = GND
  RBT_RXD1  = UART_CPU0_SCM_LVC3_UART1_RX
  RBT_RXD0  = UART_CPU0_SCM_LVC3_UART1_R1_TX
  GND_OB10  = GND
  REFCLKN2  = RST_SRST_PLD_BMC_N
  REFCLKP2  = SPI_CPU0_LVC3_TPM_CS_N
  GND_OB13  = FPGA_IO3V3_RSVD_1
  RBT_CRS_DV  = FM_SOL_UART_CH_SEL_R

(kicad_pcb
	(version 20260206)
	(generator "pcbnew")
	(generator_version "10.0")
	(general
		(thickness 1.6)
		(legacy_teardrops no)
	)
	(paper "A4")
	(title_block
		(title "04192023_DAF0TMB3IC0_F0TG_MB_C_brd_V02_OCP.brd")
		(comment 1 "Grand Teton / footprint 3166 of 8354 (J41), pads 132-175 of 175")
	)
	(layers
		(0 "F.Cu" signal "TOP")
		(4 "In1.Cu" signal "GND")
		(6 "In2.Cu" signal "IN1")
		(8 "In3.Cu" signal "GND1")
		(10 "In4.Cu" signal "IN2")
		(12 "In5.Cu" signal "GND2")
		(14 "In6.Cu" signal "IN3")
		(16 "In7.Cu" signal "GND3")
		(18 "In8.Cu" signal "VCC")
		(20 "In9.Cu" signal "VCC1")
		(22 "In10.Cu" signal "GND4")
		(24 "In11.Cu" signal "IN4")
		(26 "In12.Cu" signal "GND5")
		(28 "In13.Cu" signal "IN5")
		(30 "In14.Cu" signal "GND6")
		(32 "In15.Cu" signal "IN6")
		(34 "In16.Cu" signal "GND7")
		(2 "B.Cu" signal "BOTTOM")
		(9 "F.Adhes" user "F.Adhesive")
		(11 "B.Adhes" user "B.Adhesive")
		(13 "F.Paste" user "Package Geometry/Pastemask Top")
		(15 "B.Paste" user "Package Geometry/Pastemask Bottom")
		(5 "F.SilkS" user "Ref Des/Silkscreen Top")
		(7 "B.SilkS" user "Ref Des/Silkscreen Bottom")
		(1 "F.Mask" user "Board Geometry/Soldermask Top")
		(3 "B.Mask" user "Board Geometry/Soldermask Bottom")
		(17 "Dwgs.User" user "User.Drawings")
		(19 "Cmts.User" user "User.Comments")
		(21 "Eco1.User" user "User.Eco1")
		(23 "Eco2.User" user "User.Eco2")
		(25 "Edge.Cuts" user "Board Geometry/Outline")
		(27 "Margin" user)
		(31 "F.CrtYd" user "Package Geometry/Place Bound Top")
		(29 "B.CrtYd" user "Package Geometry/Place Bound Bottom")
		(35 "F.Fab" user "Ref Des/Assembly Top")
		(33 "B.Fab" user "Ref Des/Assembly Bottom")
	)
	(footprint ""
		(layer "F.Cu")
		(at 160.402016 -10.849864 -90)
		(property "Reference" "J41"
			(at -8.65886 -21.78558 0)
			(unlocked yes)
			(layer "F.SilkS")
			(effects
				(font
					(size 0.7874 0.5842)
					(thickness 0.1524)
				)
				(justify left)
			)
		)
		(property "Value" ""
			(at 0 0 270)
			(layer "F.Fab")
			(effects
				(font
					(size 1.27 1.27)
				)
			)
		)
		(duplicate_pad_numbers_are_jumpers no)
		(pad "B60" smd rect
			(at -5.700014 24.655018 180)
			(size 0.381 1.4478)
			(layers "F.Cu" "F.Mask" "F.Paste")
			(net "USB3_CPU0_BMC_TX_BUF_C_DN")
		)
		(pad "B61" smd rect
			(at -5.700014 25.254966 180)
			(size 0.381 1.4478)
			(layers "F.Cu" "F.Mask" "F.Paste")
			(net "GND")
		)
		(pad "B62" smd rect
			(at -5.700014 25.854914 180)
			(size 0.381 1.4478)
			(layers "F.Cu" "F.Mask" "F.Paste")
			(net "TP_PCIE_TXP<1>")
		)
		(pad "B63" smd rect
			(at -5.700014 26.455116 180)
			(size 0.381 1.4478)
			(layers "F.Cu" "F.Mask" "F.Paste")
			(net "TP_PCIE_TXN<1>")
		)
		(pad "B64" smd rect
			(at -5.700014 27.055064 180)
			(size 0.381 1.4478)
			(layers "F.Cu" "F.Mask" "F.Paste")
			(net "GND")
		)
		(pad "B65" smd rect
			(at -5.700014 27.655012 180)
			(size 0.381 1.4478)
			(layers "F.Cu" "F.Mask" "F.Paste")
			(net "P2E_MB_BMC_TX_C_DP<0>")
		)
		(pad "B66" smd rect
			(at -5.700014 28.25496 180)
			(size 0.381 1.4478)
			(layers "F.Cu" "F.Mask" "F.Paste")
			(net "P2E_MB_BMC_TX_C_DN<0>")
		)
		(pad "B67" smd rect
			(at -5.700014 28.854908 180)
			(size 0.381 1.4478)
			(layers "F.Cu" "F.Mask" "F.Paste")
			(net "GND")
		)
		(pad "B68" smd rect
			(at -5.700014 29.45511 180)
			(size 0.381 1.4478)
			(layers "F.Cu" "F.Mask" "F.Paste")
			(net "TP_PCIE_TXP<3>")
		)
		(pad "B69" smd rect
			(at -5.700014 30.055058 180)
			(size 0.381 1.4478)
			(layers "F.Cu" "F.Mask" "F.Paste")
			(net "TP_BEEP_LED")
		)
		(pad "B70" smd rect
			(at -5.700014 30.655006 180)
			(size 0.381 1.4478)
			(layers "F.Cu" "F.Mask" "F.Paste")
			(net "GND")
		)
		(pad "G1" thru_hole circle
			(at 2.400046 -32.759904 180)
			(size 1.6256 1.6256)
			(drill 1.1176)
			(layers "*.Cu" "*.Mask")
			(remove_unused_layers no)
			(net "GND")
			(clearance 0)
		)
		(pad "G2" thru_hole circle
			(at 2.400046 -20.379944 180)
			(size 1.6256 1.6256)
			(drill 1.1176)
			(layers "*.Cu" "*.Mask")
			(remove_unused_layers no)
			(net "GND")
			(clearance 0)
		)
		(pad "G3" thru_hole circle
			(at 2.400046 0 180)
			(size 1.6256 1.6256)
			(drill 1.1176)
			(layers "*.Cu" "*.Mask")
			(remove_unused_layers no)
			(net "GND")
			(clearance 0)
		)
		(pad "G4" thru_hole circle
			(at 2.400046 12.5349 180)
			(size 1.6256 1.6256)
			(drill 1.1176)
			(layers "*.Cu" "*.Mask")
			(remove_unused_layers no)
			(net "GND")
			(clearance 0)
		)
		(pad "G5" thru_hole circle
			(at 2.400046 32.759904 180)
			(size 1.6256 1.6256)
			(drill 1.1176)
			(layers "*.Cu" "*.Mask")
			(remove_unused_layers no)
			(net "GND")
			(clearance 0)
		)
		(pad "OA1" smd rect
			(at -2.750058 -30.660086 180)
			(size 0.381 1.4478)
			(layers "F.Cu" "F.Mask" "F.Paste")
			(net "P12V_SCM")
		)
		(pad "OA2" smd rect
			(at -2.750058 -30.059884 180)
			(size 0.381 1.4478)
			(layers "F.Cu" "F.Mask" "F.Paste")
			(net "P12V_SCM")
		)
		(pad "OA3" smd rect
			(at -2.750058 -29.459936 180)
			(size 0.381 1.4478)
			(layers "F.Cu" "F.Mask" "F.Paste")
			(net "GND")
		)
		(pad "OA4" smd rect
			(at -2.750058 -28.859988 180)
			(size 0.381 1.4478)
			(layers "F.Cu" "F.Mask" "F.Paste")
			(net "GND")
		)
		(pad "OA5" smd rect
			(at -2.750058 -28.26004 180)
			(size 0.381 1.4478)
			(layers "F.Cu" "F.Mask" "F.Paste")
			(net "I3C_SCM_0_SCL")
		)
		(pad "OA6" smd rect
			(at -2.750058 -27.660092 180)
			(size 0.381 1.4478)
			(layers "F.Cu" "F.Mask" "F.Paste")
			(net "I3C_SCM_0_SDA")
		)
		(pad "OA7" smd rect
			(at -2.750058 -27.05989 180)
			(size 0.381 1.4478)
			(layers "F.Cu" "F.Mask" "F.Paste")
			(net "I3C_SCM_1_SCL")
		)
		(pad "OA8" smd rect
			(at -2.750058 -26.459942 180)
			(size 0.381 1.4478)
			(layers "F.Cu" "F.Mask" "F.Paste")
			(net "I3C_SCM_1_SDA")
		)
		(pad "OA9" smd rect
			(at -2.750058 -25.859994 180)
			(size 0.381 1.4478)
			(layers "F.Cu" "F.Mask" "F.Paste")
			(net "I3C_SCM_2_SCL")
		)
		(pad "OA10" smd rect
			(at -2.750058 -25.260046 180)
			(size 0.381 1.4478)
			(layers "F.Cu" "F.Mask" "F.Paste")
			(net "I3C_SCM_2_SDA")
		)
		(pad "OA11" smd rect
			(at -2.750058 -24.660098 180)
			(size 0.381 1.4478)
			(layers "F.Cu" "F.Mask" "F.Paste")
			(net "I3C_SCM_3_SCL")
		)
		(pad "OA12" smd rect
			(at -2.750058 -24.059896 180)
			(size 0.381 1.4478)
			(layers "F.Cu" "F.Mask" "F.Paste")
			(net "I3C_SCM_3_SDA")
		)
		(pad "OA13" smd rect
			(at -2.750058 -23.459948 180)
			(size 0.381 1.4478)
			(layers "F.Cu" "F.Mask" "F.Paste")
			(net "GND")
		)
		(pad "OA14" smd rect
			(at -2.750058 -22.86 180)
			(size 0.381 1.4478)
			(layers "F.Cu" "F.Mask" "F.Paste")
			(net "VIRTUAL_RESEAT")
		)
		(pad "OB1" smd rect
			(at -5.700014 -30.660086 180)
			(size 0.381 1.4478)
			(layers "F.Cu" "F.Mask" "F.Paste")
			(net "P12V_SCM")
		)
		(pad "OB2" smd rect
			(at -5.700014 -30.059884 180)
			(size 0.381 1.4478)
			(layers "F.Cu" "F.Mask" "F.Paste")
			(net "P12V_SCM")
		)
		(pad "OB3" smd rect
			(at -5.700014 -29.459936 180)
			(size 0.381 1.4478)
			(layers "F.Cu" "F.Mask" "F.Paste")
			(net "PRSNT0_N")
		)
		(pad "OB4" smd rect
			(at -5.700014 -28.859988 180)
			(size 0.381 1.4478)
			(layers "F.Cu" "F.Mask" "F.Paste")
			(net "GND")
		)
		(pad "OB5" smd rect
			(at -5.700014 -28.26004 180)
			(size 0.381 1.4478)
			(layers "F.Cu" "F.Mask" "F.Paste")
			(net "UART_BMC_BIC_TX")
		)
		(pad "OB6" smd rect
			(at -5.700014 -27.660092 180)
			(size 0.381 1.4478)
			(layers "F.Cu" "F.Mask" "F.Paste")
			(net "UART_BMC_BIC_BUF_RX")
		)
		(pad "OB7" smd rect
			(at -5.700014 -27.05989 180)
			(size 0.381 1.4478)
			(layers "F.Cu" "F.Mask" "F.Paste")
			(net "GND")
		)
		(pad "OB8" smd rect
			(at -5.700014 -26.459942 180)
			(size 0.381 1.4478)
			(layers "F.Cu" "F.Mask" "F.Paste")
			(net "UART_CPU0_SCM_LVC3_UART1_RX")
		)
		(pad "OB9" smd rect
			(at -5.700014 -25.859994 180)
			(size 0.381 1.4478)
			(layers "F.Cu" "F.Mask" "F.Paste")
			(net "UART_CPU0_SCM_LVC3_UART1_R1_TX")
		)
		(pad "OB10" smd rect
			(at -5.700014 -25.260046 180)
			(size 0.381 1.4478)
			(layers "F.Cu" "F.Mask" "F.Paste")
			(net "GND")
		)
		(pad "OB11" smd rect
			(at -5.700014 -24.660098 180)
			(size 0.381 1.4478)
			(layers "F.Cu" "F.Mask" "F.Paste")
			(net "RST_SRST_PLD_BMC_N")
		)
		(pad "OB12" smd rect
			(at -5.700014 -24.059896 180)
			(size 0.381 1.4478)
			(layers "F.Cu" "F.Mask" "F.Paste")
			(net "SPI_CPU0_LVC3_TPM_CS_N")
		)
		(pad "OB13" smd rect
			(at -5.700014 -23.459948 180)
			(size 0.381 1.4478)
			(layers "F.Cu" "F.Mask" "F.Paste")
			(net "FPGA_IO3V3_RSVD_1")
		)
		(pad "OB14" smd rect
			(at -5.700014 -22.86 180)
			(size 0.381 1.4478)
			(layers "F.Cu" "F.Mask" "F.Paste")
			(net "FM_SOL_UART_CH_SEL_R")
		)
	)
)
